(kicad_pcb
	(version 20260206)
	(generator "pcbnew")
	(generator_version "10.0")
	(general
		(thickness 1.6)
		(legacy_teardrops no)
	)
	(paper "A4")
	(title_block
		(title "netronome-mezz — pcbd0082-001_rev01_jul9_a.brd")
		(comment 1 "Open CloudServer (Microsoft) / footprints 369-372 of 714")
	)
	(layers
		(0 "F.Cu" signal "TOP")
		(4 "In1.Cu" signal "02_GND")
		(6 "In2.Cu" signal "03_SIG")
		(8 "In3.Cu" signal "04_SIG")
		(10 "In4.Cu" signal "05_GND")
		(12 "In5.Cu" signal "06_PWR1")
		(14 "In6.Cu" signal "07_SIG")
		(16 "In7.Cu" signal "08_SIG")
		(18 "In8.Cu" signal "09_GND")
		(2 "B.Cu" signal "BOTTOM")
		(9 "F.Adhes" user "F.Adhesive")
		(11 "B.Adhes" user "B.Adhesive")
		(13 "F.Paste" user "Package Geometry/Pastemask Top")
		(15 "B.Paste" user "Package Geometry/Pastemask Bottom")
		(5 "F.SilkS" user "Ref Des/Silkscreen Top")
		(7 "B.SilkS" user "Ref Des/Silkscreen Bottom")
		(1 "F.Mask" user "Board Geometry/Soldermask Top")
		(3 "B.Mask" user "Board Geometry/Soldermask Bottom")
		(17 "Dwgs.User" user "User.Drawings")
		(19 "Cmts.User" user "User.Comments")
		(21 "Eco1.User" user "User.Eco1")
		(23 "Eco2.User" user "User.Eco2")
		(25 "Edge.Cuts" user "Board Geometry/Outline")
		(27 "Margin" user)
		(31 "F.CrtYd" user "Package Geometry/Place Bound Top")
		(29 "B.CrtYd" user "Package Geometry/Place Bound Bottom")
		(35 "F.Fab" user "Ref Des/Assembly Top")
		(33 "B.Fab" user "Ref Des/Assembly Bottom")
		(45 "User.4" user "COMPVAL_TYPE_BOTTOM")
	)
	(footprint ""
		(layer "B.Cu")
		(at 40.64 28.829)
		(property "Reference" "R408"
			(at -0.02667 3.683 270)
			(unlocked yes)
			(layer "B.SilkS")
			(effects
				(font
					(size 0.7874 0.5842)
					(thickness 0.127)
				)
				(justify left mirror)
			)
		)
		(property "Value" "4.75K"
			(at 0.148158 1.3462 270)
			(unlocked yes)
			(layer "B.Fab")
			(hide yes)
			(effects
				(font
					(size 1.27 0.9652)
					(thickness 0.000001)
				)
				(justify left mirror)
			)
		)
		(property "Device Type" "REST4024"
			(at 0.148158 1.3462 270)
			(unlocked yes)
			(layer "B.Fab")
			(hide yes)
			(effects
				(font
					(size 1.27 0.9652)
					(thickness 0.000001)
				)
				(justify left mirror)
			)
		)
		(duplicate_pad_numbers_are_jumpers no)
		(fp_poly
			(pts
				(xy -0.635 1.0668) (xy -0.635 -1.0668) (xy 0.635 -1.0668) (xy 0.635 1.0668)
			)
			(stroke
				(width 0)
				(type default)
			)
			(fill no)
			(layer "B.CrtYd")
		)
		(fp_line
			(start -0.254 -0.508)
			(end -0.254 0.508)
			(stroke
				(width 0.0254)
				(type default)
			)
			(layer "B.Fab")
		)
		(fp_line
			(start -0.254 0.508)
			(end 0.254 0.508)
			(stroke
				(width 0.0254)
				(type default)
			)
			(layer "B.Fab")
		)
		(fp_line
			(start 0.254 -0.508)
			(end -0.254 -0.508)
			(stroke
				(width 0.0254)
				(type default)
			)
			(layer "B.Fab")
		)
		(fp_line
			(start 0.254 0.508)
			(end 0.254 -0.508)
			(stroke
				(width 0.0254)
				(type default)
			)
			(layer "B.Fab")
		)
		(pad "1" smd rect
			(at 0 -0.4191 180)
			(size 0.508 0.5334)
			(layers "B.Cu" "B.Mask" "B.Paste")
			(net "NFP_JTAG_ARM_TCK")
		)
		(pad "2" smd rect
			(at 0 0.4191 180)
			(size 0.508 0.5334)
			(layers "B.Cu" "B.Mask" "B.Paste")
			(net "GND")
		)
		(zone
			(layer "B.Cu")
			(hatch none 0.5)
			(connect_pads
				(clearance 0)
			)
			(min_thickness 0.25)
			(keepout
				(tracks not_allowed)
				(vias allowed)
				(pads allowed)
				(copperpour not_allowed)
				(footprints allowed)
			)
			(placement
				(enabled no)
				(sheetname "")
			)
			(fill
				(thermal_gap 0.5)
				(thermal_bridge_width 0.5)
				(island_removal_mode 0)
			)
			(polygon
				(pts
					(xy 40.6146 28.8036) (xy 40.6146 28.8544) (xy 40.6654 28.8544) (xy 40.6654 28.8036)
				)
			)
		)
	)
	(footprint ""
		(layer "B.Cu")
		(at 80.250995 29.812996)
		(property "Reference" "V3_A-A10"
			(at 0 0 0)
			(layer "B.SilkS")
			(hide yes)
			(effects
				(font
					(size 1.27 1.27)
				)
				(justify mirror)
			)
		)
		(property "Value" ""
			(at 0 0 0)
			(layer "B.Fab")
			(effects
				(font
					(size 1.27 1.27)
				)
				(justify mirror)
			)
		)
		(duplicate_pad_numbers_are_jumpers no)
		(pad "1" thru_hole circle
			(at 0 0 180)
			(size 0.4572 0.4572)
			(drill 0.20574)
			(layers "*.Cu" "*.Mask")
			(remove_unused_layers no)
			(net "DDR0_32A_A10")
			(clearance 0.1143)
			(thermal_gap 0.1143)
		)
	)
	(footprint ""
		(layer "B.Cu")
		(at 30.988 5.588 180)
		(property "Reference" "C36"
			(at 0.02667 0.889 270)
			(unlocked yes)
			(layer "B.SilkS")
			(effects
				(font
					(size 0.7874 0.5842)
					(thickness 0.127)
				)
				(justify left mirror)
			)
		)
		(property "Value" "10UF"
			(at 0.091846 0.2921 90)
			(unlocked yes)
			(layer "B.Fab")
			(hide yes)
			(effects
				(font
					(size 0.7874 0.5842)
					(thickness 0.2032)
				)
				(justify left mirror)
			)
		)
		(property "Device Type" "CAPC0064"
			(at 0.091846 0.2921 90)
			(unlocked yes)
			(layer "B.Fab")
			(hide yes)
			(effects
				(font
					(size 0.7874 0.5842)
					(thickness 0.2032)
				)
				(justify left mirror)
			)
		)
		(duplicate_pad_numbers_are_jumpers no)
		(fp_poly
			(pts
				(xy -0.635 1.0668) (xy -0.635 -1.0668) (xy 0.635 -1.0668) (xy 0.635 1.0668)
			)
			(stroke
				(width 0)
				(type default)
			)
			(fill no)
			(layer "B.CrtYd")
		)
		(fp_line
			(start 0.254 0.508)
			(end 0.254 -0.508)
			(stroke
				(width 0.0254)
				(type default)
			)
			(layer "B.Fab")
		)
		(fp_line
			(start 0.254 -0.508)
			(end -0.254 -0.508)
			(stroke
				(width 0.0254)
				(type default)
			)
			(layer "B.Fab")
		)
		(fp_line
			(start -0.254 0.508)
			(end 0.254 0.508)
			(stroke
				(width 0.0254)
				(type default)
			)
			(layer "B.Fab")
		)
		(fp_line
			(start -0.254 -0.508)
			(end -0.254 0.508)
			(stroke
				(width 0.0254)
				(type default)
			)
			(layer "B.Fab")
		)
		(pad "1" smd rect
			(at 0 -0.4191)
			(size 0.508 0.5334)
			(layers "B.Cu" "B.Mask" "B.Paste")
			(net "EXT_3.3V")
		)
		(pad "2" smd rect
			(at 0 0.4191)
			(size 0.508 0.5334)
			(layers "B.Cu" "B.Mask" "B.Paste")
			(net "GND")
		)
		(zone
			(layer "B.Cu")
			(hatch none 0.5)
			(connect_pads
				(clearance 0)
			)
			(min_thickness 0.25)
			(keepout
				(tracks not_allowed)
				(vias allowed)
				(pads allowed)
				(copperpour not_allowed)
				(footprints allowed)
			)
			(placement
				(enabled no)
				(sheetname "")
			)
			(fill
				(thermal_gap 0.5)
				(thermal_bridge_width 0.5)
				(island_removal_mode 0)
			)
			(polygon
				(pts
					(xy 31.0134 5.6134) (xy 31.0134 5.5626) (xy 30.9626 5.5626) (xy 30.9626 5.6134)
				)
			)
		)
	)
	(footprint ""
		(layer "B.Cu")
		(at 3.3655 11.176 90)
		(property "Reference" "R388"
			(at 0 0 90)
			(layer "B.SilkS")
			(hide yes)
			(effects
				(font
					(size 1.27 1.27)
				)
				(justify mirror)
			)
		)
		(property "Value" "0"
			(at 0.148158 1.3462 0)
			(unlocked yes)
			(layer "B.Fab")
			(hide yes)
			(effects
				(font
					(size 1.27 0.9652)
					(thickness 0.000001)
				)
				(justify left mirror)
			)
		)
		(property "Device Type" "REST1111"
			(at 0.148158 1.3462 0)
			(unlocked yes)
			(layer "B.Fab")
			(hide yes)
			(effects
				(font
					(size 1.27 0.9652)
					(thickness 0.000001)
				)
				(justify left mirror)
			)
		)
		(duplicate_pad_numbers_are_jumpers no)
		(fp_poly
			(pts
				(xy -0.635 1.0668) (xy -0.635 -1.0668) (xy 0.635 -1.0668) (xy 0.635 1.0668)
			)
			(stroke
				(width 0)
				(type default)
			)
			(fill no)
			(layer "B.CrtYd")
		)
		(fp_line
			(start 0.254 -0.508)
			(end -0.254 -0.508)
			(stroke
				(width 0.0254)
				(type default)
			)
			(layer "B.Fab")
		)
		(fp_line
			(start -0.254 -0.508)
			(end -0.254 0.508)
			(stroke
				(width 0.0254)
				(type default)
			)
			(layer "B.Fab")
		)
		(fp_line
			(start 0.254 0.508)
			(end 0.254 -0.508)
			(stroke
				(width 0.0254)
				(type default)
			)
			(layer "B.Fab")
		)
		(fp_line
			(start -0.254 0.508)
			(end 0.254 0.508)
			(stroke
				(width 0.0254)
				(type default)
			)
			(layer "B.Fab")
		)
		(pad "1" smd rect
			(at 0 -0.4191 270)
			(size 0.508 0.5334)
			(layers "B.Cu" "B.Mask" "B.Paste")
			(net "NWK1_I2C_SDA")
		)
		(pad "2" smd rect
			(at 0 0.4191 270)
			(size 0.508 0.5334)
			(layers "B.Cu" "B.Mask" "B.Paste")
			(net "MUX_NFP_GPIO3_NWK1_I2C_SDA")
		)
		(zone
			(layer "B.Cu")
			(hatch none 0.5)
			(connect_pads
				(clearance 0)
			)
			(min_thickness 0.25)
			(keepout
				(tracks not_allowed)
				(vias allowed)
				(pads allowed)
				(copperpour not_allowed)
				(footprints allowed)
			)
			(placement
				(enabled no)
				(sheetname "")
			)
			(fill
				(thermal_gap 0.5)
				(thermal_bridge_width 0.5)
				(island_removal_mode 0)
			)
			(polygon
				(pts
					(xy 3.3401 11.2014) (xy 3.3909 11.2014) (xy 3.3909 11.1506) (xy 3.3401 11.1506)
				)
			)
		)
	)
)
